FILE_TYPE = CONNECTIVITY;
{Allegro Design Entry HDL 16.6-p007 (v16-6-112F) 10/10/2012}
"PAGE_NUMBER" = 266;
0"NC";
END.
